# S9S_MB_2U (Grand Teton) — schematic netlist excerpt (pin names and nets, part order shuffled) for the footprints in the layout excerpt that follows; sources: Cadence DE-HDL packaged netlist, KiCad conversion of 03242023_DA0F0TMBIJ0_F0T_Motherboard_J_brd_V01_OCP.brd

PC224  Q_CAP  10UF 6.3V 20% X6S  pkg C0402  page 274 : A = PVCCINFAON_CPU0_VREF ; B = GND
R4607  Q_RES  0 5% CHIP  pkg 0402LF  page 214 : A = LED_HDD_ACTIVITY_B_N ; B = LED_HDD_ACTIVITY_B_PLD_N

(kicad_pcb
	(version 20260206)
	(generator "pcbnew")
	(generator_version "10.0")
	(general
		(thickness 1.6)
		(legacy_teardrops no)
	)
	(paper "A4")
	(title_block
		(title "03242023_DA0F0TMBIJ0_F0T_Motherboard_J_brd_V01_OCP.brd")
		(comment 1 "Grand Teton / footprints 3216-3217 of 6105")
	)
	(layers
		(0 "F.Cu" signal "TOP")
		(4 "In1.Cu" signal "GND")
		(6 "In2.Cu" signal "IN1")
		(8 "In3.Cu" signal "GND1")
		(10 "In4.Cu" signal "IN2")
		(12 "In5.Cu" signal "GND2")
		(14 "In6.Cu" signal "IN3")
		(16 "In7.Cu" signal "GND3")
		(18 "In8.Cu" signal "VCC")
		(20 "In9.Cu" signal "VCC1")
		(22 "In10.Cu" signal "GND4")
		(24 "In11.Cu" signal "IN4")
		(26 "In12.Cu" signal "GND5")
		(28 "In13.Cu" signal "IN5")
		(30 "In14.Cu" signal "GND6")
		(32 "In15.Cu" signal "IN6")
		(34 "In16.Cu" signal "GND7")
		(2 "B.Cu" signal "BOTTOM")
		(9 "F.Adhes" user "F.Adhesive")
		(11 "B.Adhes" user "B.Adhesive")
		(13 "F.Paste" user "Package Geometry/Pastemask Top")
		(15 "B.Paste" user "Package Geometry/Pastemask Bottom")
		(5 "F.SilkS" user "Ref Des/Silkscreen Top")
		(7 "B.SilkS" user "Ref Des/Silkscreen Bottom")
		(1 "F.Mask" user "Board Geometry/Soldermask Top")
		(3 "B.Mask" user "Board Geometry/Soldermask Bottom")
		(17 "Dwgs.User" user "User.Drawings")
		(19 "Cmts.User" user "User.Comments")
		(21 "Eco1.User" user "User.Eco1")
		(23 "Eco2.User" user "User.Eco2")
		(25 "Edge.Cuts" user "Board Geometry/Outline")
		(27 "Margin" user)
		(31 "F.CrtYd" user "Package Geometry/Place Bound Top")
		(29 "B.CrtYd" user "Package Geometry/Place Bound Bottom")
		(35 "F.Fab" user "Ref Des/Assembly Top")
		(33 "B.Fab" user "Ref Des/Assembly Bottom")
	)
	(footprint ""
		(layer "F.Cu")
		(at 423.513504 -131.975352 -90)
		(property "Reference" "PC224"
			(at 0 0 270)
			(layer "F.SilkS")
			(hide yes)
			(effects
				(font
					(size 1.27 1.27)
				)
			)
		)
		(property "Value" ""
			(at 0 0 270)
			(layer "F.Fab")
			(effects
				(font
					(size 1.27 1.27)
				)
			)
		)
		(duplicate_pad_numbers_are_jumpers no)
		(fp_line
			(start -0.7874 0.4064)
			(end -0.7874 -0.4064)
			(stroke
				(width 0.1524)
				(type default)
			)
			(layer "F.SilkS")
		)
		(fp_line
			(start 0.7874 0.4064)
			(end -0.7874 0.4064)
			(stroke
				(width 0.1524)
				(type default)
			)
			(layer "F.SilkS")
		)
		(fp_line
			(start -0.7874 -0.4064)
			(end 0.7874 -0.4064)
			(stroke
				(width 0.1524)
				(type default)
			)
			(layer "F.SilkS")
		)
		(fp_line
			(start 0.7874 -0.4064)
			(end 0.7874 0.4064)
			(stroke
				(width 0.1524)
				(type default)
			)
			(layer "F.SilkS")
		)
		(fp_line
			(start -0.67945 0.3048)
			(end -0.67945 -0.305054)
			(stroke
				(width 0.1)
				(type default)
			)
			(layer "F.Fab")
		)
		(fp_line
			(start -0.12065 0.3048)
			(end -0.67945 0.3048)
			(stroke
				(width 0.1)
				(type default)
			)
			(layer "F.Fab")
		)
		(fp_line
			(start 0.120396 0.3048)
			(end 0.120396 0.2794)
			(stroke
				(width 0.1)
				(type default)
			)
			(layer "F.Fab")
		)
		(fp_line
			(start 0.67945 0.3048)
			(end 0.120396 0.3048)
			(stroke
				(width 0.1)
				(type default)
			)
			(layer "F.Fab")
		)
		(fp_line
			(start -0.12065 0.2794)
			(end -0.12065 0.3048)
			(stroke
				(width 0.1)
				(type default)
			)
			(layer "F.Fab")
		)
		(fp_line
			(start 0.120396 0.2794)
			(end -0.12065 0.2794)
			(stroke
				(width 0.1)
				(type default)
			)
			(layer "F.Fab")
		)
		(fp_line
			(start -0.12065 -0.2794)
			(end 0.12065 -0.2794)
			(stroke
				(width 0.1)
				(type default)
			)
			(layer "F.Fab")
		)
		(fp_line
			(start 0.12065 -0.2794)
			(end 0.12065 -0.3048)
			(stroke
				(width 0.1)
				(type default)
			)
			(layer "F.Fab")
		)
		(fp_line
			(start 0.12065 -0.3048)
			(end 0.67945 -0.3048)
			(stroke
				(width 0.1)
				(type default)
			)
			(layer "F.Fab")
		)
		(fp_line
			(start 0.67945 -0.3048)
			(end 0.67945 0.3048)
			(stroke
				(width 0.1)
				(type default)
			)
			(layer "F.Fab")
		)
		(fp_line
			(start -0.67945 -0.305054)
			(end -0.12065 -0.305054)
			(stroke
				(width 0.1)
				(type default)
			)
			(layer "F.Fab")
		)
		(fp_line
			(start -0.12065 -0.305054)
			(end -0.12065 -0.2794)
			(stroke
				(width 0.1)
				(type default)
			)
			(layer "F.Fab")
		)
		(pad "1" smd circle
			(at -0.40005 0 270)
			(size 0 0)
			(layers "F.Cu" "F.Mask" "F.Paste")
			(net "PVCCINFAON_CPU0_VREF")
		)
		(pad "2" smd circle
			(at 0.40005 0 270)
			(size 0 0)
			(layers "F.Cu" "F.Mask" "F.Paste")
			(net "GND")
		)
	)
	(footprint ""
		(layer "F.Cu")
		(at 193.4718 -130.419348 90)
		(property "Reference" "R4607"
			(at 0 0 90)
			(layer "F.SilkS")
			(hide yes)
			(effects
				(font
					(size 1.27 1.27)
				)
			)
		)
		(property "Value" ""
			(at 0 0 90)
			(layer "F.Fab")
			(effects
				(font
					(size 1.27 1.27)
				)
			)
		)
		(duplicate_pad_numbers_are_jumpers no)
		(fp_line
			(start 0.7874 -0.4064)
			(end 0.7874 0.4064)
			(stroke
				(width 0.1524)
				(type default)
			)
			(layer "F.SilkS")
		)
		(fp_line
			(start -0.7874 -0.4064)
			(end 0.7874 -0.4064)
			(stroke
				(width 0.1524)
				(type default)
			)
			(layer "F.SilkS")
		)
		(fp_line
			(start 0.7874 0.4064)
			(end -0.7874 0.4064)
			(stroke
				(width 0.1524)
				(type default)
			)
			(layer "F.SilkS")
		)
		(fp_line
			(start -0.7874 0.4064)
			(end -0.7874 -0.4064)
			(stroke
				(width 0.1524)
				(type default)
			)
			(layer "F.SilkS")
		)
		(fp_line
			(start -0.12065 -0.305054)
			(end -0.12065 -0.2794)
			(stroke
				(width 0.1)
				(type default)
			)
			(layer "F.Fab")
		)
		(fp_line
			(start -0.67945 -0.305054)
			(end -0.12065 -0.305054)
			(stroke
				(width 0.1)
				(type default)
			)
			(layer "F.Fab")
		)
		(fp_line
			(start 0.67945 -0.3048)
			(end 0.67945 0.3048)
			(stroke
				(width 0.1)
				(type default)
			)
			(layer "F.Fab")
		)
		(fp_line
			(start 0.12065 -0.3048)
			(end 0.67945 -0.3048)
			(stroke
				(width 0.1)
				(type default)
			)
			(layer "F.Fab")
		)
		(fp_line
			(start 0.12065 -0.2794)
			(end 0.12065 -0.3048)
			(stroke
				(width 0.1)
				(type default)
			)
			(layer "F.Fab")
		)
		(fp_line
			(start -0.12065 -0.2794)
			(end 0.12065 -0.2794)
			(stroke
				(width 0.1)
				(type default)
			)
			(layer "F.Fab")
		)
		(fp_line
			(start 0.120396 0.2794)
			(end -0.12065 0.2794)
			(stroke
				(width 0.1)
				(type default)
			)
			(layer "F.Fab")
		)
		(fp_line
			(start -0.12065 0.2794)
			(end -0.12065 0.3048)
			(stroke
				(width 0.1)
				(type default)
			)
			(layer "F.Fab")
		)
		(fp_line
			(start 0.67945 0.3048)
			(end 0.120396 0.3048)
			(stroke
				(width 0.1)
				(type default)
			)
			(layer "F.Fab")
		)
		(fp_line
			(start 0.120396 0.3048)
			(end 0.120396 0.2794)
			(stroke
				(width 0.1)
				(type default)
			)
			(layer "F.Fab")
		)
		(fp_line
			(start -0.12065 0.3048)
			(end -0.67945 0.3048)
			(stroke
				(width 0.1)
				(type default)
			)
			(layer "F.Fab")
		)
		(fp_line
			(start -0.67945 0.3048)
			(end -0.67945 -0.305054)
			(stroke
				(width 0.1)
				(type default)
			)
			(layer "F.Fab")
		)
		(pad "1" smd circle
			(at -0.40005 0 90)
			(size 0 0)
			(layers "F.Cu" "F.Mask" "F.Paste")
			(net "LED_HDD_ACTIVITY_B_N")
		)
		(pad "2" smd circle
			(at 0.40005 0 90)
			(size 0 0)
			(layers "F.Cu" "F.Mask" "F.Paste")
			(net "LED_HDD_ACTIVITY_B_PLD_N")
		)
	)
)
